FILE_TYPE = CONNECTIVITY;
{Allegro Design Entry HDL 17.4-2019 S026 (4007227) 1/17/2022}
"PAGE_NUMBER" = 35;
0"NC";
END.
